(kicad_pcb
	(version 20260206)
	(generator "pcbnew")
	(generator_version "10.0")
	(general
		(thickness 1.6)
		(legacy_teardrops no)
	)
	(paper "A4")
	(title_block
		(title "Bryce Canyon_SCC_16316-1_OCP.brd")
		(comment 1 "Bryce Canyon / footprints 845-853 of 1561")
	)
	(layers
		(0 "F.Cu" signal "TOP")
		(4 "In1.Cu" signal "L2GND")
		(6 "In2.Cu" signal "L3")
		(8 "In3.Cu" signal "L4VCC")
		(10 "In4.Cu" signal "L5VCC")
		(12 "In5.Cu" signal "L6")
		(14 "In6.Cu" signal "L7GND")
		(2 "B.Cu" signal "BOTTOM")
		(9 "F.Adhes" user "F.Adhesive")
		(11 "B.Adhes" user "B.Adhesive")
		(13 "F.Paste" user "Package Geometry/Pastemask Top")
		(15 "B.Paste" user "Package Geometry/Pastemask Bottom")
		(5 "F.SilkS" user "Ref Des/Silkscreen Top")
		(7 "B.SilkS" user "Ref Des/Silkscreen Bottom")
		(1 "F.Mask" user "Board Geometry/Soldermask Top")
		(3 "B.Mask" user "Board Geometry/Soldermask Bottom")
		(17 "Dwgs.User" user "User.Drawings")
		(19 "Cmts.User" user "User.Comments")
		(21 "Eco1.User" user "User.Eco1")
		(23 "Eco2.User" user "User.Eco2")
		(25 "Edge.Cuts" user "Board Geometry/Outline")
		(27 "Margin" user)
		(31 "F.CrtYd" user "Package Geometry/Place Bound Top")
		(29 "B.CrtYd" user "Package Geometry/Place Bound Bottom")
		(35 "F.Fab" user "Ref Des/Assembly Top")
		(33 "B.Fab" user "Ref Des/Assembly Bottom")
	)
	(footprint ""
		(layer "B.Cu")
		(at 183.21528 -32.40913)
		(property "Reference" "C459"
			(at 0 0 0)
			(layer "B.SilkS")
			(hide yes)
			(effects
				(font
					(size 1.27 1.27)
				)
				(justify mirror)
			)
		)
		(property "Value" "SCD1U6D3V1KX-GP"
			(at 2.8321 -1.7399 0)
			(unlocked yes)
			(layer "B.Fab")
			(hide yes)
			(effects
				(font
					(size 1.016 1.016)
					(thickness 0.1524)
				)
				(justify mirror)
			)
		)
		(property "Device Type" "C0201H13"
			(at 2.8321 -3.2639 0)
			(unlocked yes)
			(layer "B.Fab")
			(hide yes)
			(effects
				(font
					(size 1.016 1.016)
					(thickness 0.1524)
				)
				(justify mirror)
			)
		)
		(duplicate_pad_numbers_are_jumpers no)
		(fp_rect
			(start 0.2794 0.6477)
			(end -0.2794 -0.6477)
			(stroke
				(width 0)
				(type default)
			)
			(fill no)
			(layer "B.CrtYd")
		)
		(fp_rect
			(start 0.2794 0.6477)
			(end -0.2794 -0.6477)
			(stroke
				(width 0)
				(type default)
			)
			(fill no)
			(layer "B.Fab")
		)
		(pad "1" smd custom
			(at 0 -0.2794 180)
			(size 0.0762 0.0762)
			(layers "B.Cu" "B.Mask" "B.Paste")
			(net "P1V8_C")
			(options
				(clearance outline)
				(anchor circle)
			)
			(primitives
				(gr_poly
					(pts
						(arc
							(start 0.1524 0.127)
							(mid 0.137521 0.162921)
							(end 0.1016 0.1778)
						)
						(arc
							(start -0.1016 0.1778)
							(mid -0.137521 0.162921)
							(end -0.1524 0.127)
						)
						(arc
							(start -0.1524 -0.127)
							(mid -0.137521 -0.162921)
							(end -0.1016 -0.1778)
						)
						(arc
							(start 0.1016 -0.1778)
							(mid 0.137521 -0.162921)
							(end 0.1524 -0.127)
						)
					)
					(width 0)
					(fill yes)
				)
			)
		)
		(pad "2" smd custom
			(at 0 0.2794 180)
			(size 0.0762 0.0762)
			(layers "B.Cu" "B.Mask" "B.Paste")
			(net "GND")
			(options
				(clearance outline)
				(anchor circle)
			)
			(primitives
				(gr_poly
					(pts
						(arc
							(start 0.1524 0.127)
							(mid 0.137521 0.162921)
							(end 0.1016 0.1778)
						)
						(arc
							(start -0.1016 0.1778)
							(mid -0.137521 0.162921)
							(end -0.1524 0.127)
						)
						(arc
							(start -0.1524 -0.127)
							(mid -0.137521 -0.162921)
							(end -0.1016 -0.1778)
						)
						(arc
							(start 0.1016 -0.1778)
							(mid 0.137521 -0.162921)
							(end 0.1524 -0.127)
						)
					)
					(width 0)
					(fill yes)
				)
			)
		)
	)
	(footprint ""
		(layer "B.Cu")
		(at 184.412128 -52.299616 -90)
		(property "Reference" "TP111"
			(at 0 0 90)
			(layer "B.SilkS")
			(hide yes)
			(effects
				(font
					(size 1.27 1.27)
				)
				(justify mirror)
			)
		)
		(property "Value" "TPAD28-2-GP"
			(at 0.0127 -1.6637 270)
			(unlocked yes)
			(layer "B.Fab")
			(hide yes)
			(effects
				(font
					(size 1.016 1.016)
					(thickness 0.1524)
				)
				(justify mirror)
			)
		)
		(property "Device Type" "TPAD28"
			(at 0.0127 -3.1877 270)
			(unlocked yes)
			(layer "B.Fab")
			(hide yes)
			(effects
				(font
					(size 1.016 1.016)
					(thickness 0.1524)
				)
				(justify mirror)
			)
		)
		(duplicate_pad_numbers_are_jumpers no)
		(fp_poly
			(pts
				(arc
					(start 0 -0.3556)
					(mid 0 0.3556)
					(end 0 -0.3556)
				)
			)
			(stroke
				(width 0)
				(type default)
			)
			(fill no)
			(layer "B.CrtYd")
		)
		(fp_poly
			(pts
				(arc
					(start 0 -0.6096)
					(mid 0 0.6096)
					(end 0 -0.6096)
				)
			)
			(stroke
				(width 0)
				(type default)
			)
			(fill no)
			(layer "B.Fab")
		)
		(pad "1" smd circle
			(at 0 0 90)
			(size 0.7112 0.7112)
			(layers "B.Cu" "B.Mask" "B.Paste")
			(net "XM_ALE")
		)
	)
	(footprint ""
		(layer "B.Cu")
		(at 111.499904 -76.499974)
		(property "Reference" "TP48"
			(at 0 0 0)
			(layer "B.SilkS")
			(hide yes)
			(effects
				(font
					(size 1.27 1.27)
				)
				(justify mirror)
			)
		)
		(property "Value" "TPAD28-2-GP"
			(at 0.0127 -1.6637 0)
			(unlocked yes)
			(layer "B.Fab")
			(hide yes)
			(effects
				(font
					(size 1.016 1.016)
					(thickness 0.1524)
				)
				(justify mirror)
			)
		)
		(property "Device Type" "TPAD28"
			(at 0.0127 -3.1877 0)
			(unlocked yes)
			(layer "B.Fab")
			(hide yes)
			(effects
				(font
					(size 1.016 1.016)
					(thickness 0.1524)
				)
				(justify mirror)
			)
		)
		(duplicate_pad_numbers_are_jumpers no)
		(fp_poly
			(pts
				(arc
					(start 0.3556 0)
					(mid -0.3556 0)
					(end 0.3556 0)
				)
			)
			(stroke
				(width 0)
				(type default)
			)
			(fill no)
			(layer "B.CrtYd")
		)
		(fp_poly
			(pts
				(arc
					(start 0.6096 0)
					(mid -0.6096 0)
					(end 0.6096 0)
				)
			)
			(stroke
				(width 0)
				(type default)
			)
			(fill no)
			(layer "B.Fab")
		)
		(pad "1" smd circle
			(at 0 0 180)
			(size 0.7112 0.7112)
			(layers "B.Cu" "B.Mask" "B.Paste")
			(net "XM_GP_CS_2#_TP")
		)
	)
	(footprint ""
		(layer "B.Cu")
		(at 96.497394 -52.347368 90)
		(property "Reference" "C92"
			(at 0 0 90)
			(layer "B.SilkS")
			(hide yes)
			(effects
				(font
					(size 1.27 1.27)
				)
				(justify mirror)
			)
		)
		(property "Value" "SCD01U16V1KX-GP"
			(at 2.8321 -1.7399 90)
			(unlocked yes)
			(layer "B.Fab")
			(hide yes)
			(effects
				(font
					(size 1.016 1.016)
					(thickness 0.1524)
				)
				(justify mirror)
			)
		)
		(property "Device Type" "C0201H13"
			(at 2.8321 -3.2639 90)
			(unlocked yes)
			(layer "B.Fab")
			(hide yes)
			(effects
				(font
					(size 1.016 1.016)
					(thickness 0.1524)
				)
				(justify mirror)
			)
		)
		(duplicate_pad_numbers_are_jumpers no)
		(fp_rect
			(start 0.2794 0.6477)
			(end -0.2794 -0.6477)
			(stroke
				(width 0)
				(type default)
			)
			(fill no)
			(layer "B.CrtYd")
		)
		(fp_rect
			(start 0.2794 0.6477)
			(end -0.2794 -0.6477)
			(stroke
				(width 0)
				(type default)
			)
			(fill no)
			(layer "B.Fab")
		)
		(pad "1" smd custom
			(at 0 -0.2794 270)
			(size 0.0762 0.0762)
			(layers "B.Cu" "B.Mask" "B.Paste")
			(net "PHY_DPB_TO_SCC_14_DN")
			(options
				(clearance outline)
				(anchor circle)
			)
			(primitives
				(gr_poly
					(pts
						(arc
							(start 0.1524 0.127)
							(mid 0.137521 0.162921)
							(end 0.1016 0.1778)
						)
						(arc
							(start -0.1016 0.1778)
							(mid -0.137521 0.162921)
							(end -0.1524 0.127)
						)
						(arc
							(start -0.1524 -0.127)
							(mid -0.137521 -0.162921)
							(end -0.1016 -0.1778)
						)
						(arc
							(start 0.1016 -0.1778)
							(mid 0.137521 -0.162921)
							(end 0.1524 -0.127)
						)
					)
					(width 0)
					(fill yes)
				)
			)
		)
		(pad "2" smd custom
			(at 0 0.2794 270)
			(size 0.0762 0.0762)
			(layers "B.Cu" "B.Mask" "B.Paste")
			(net "PHY_DPB_TO_SCC_C_14_DN")
			(options
				(clearance outline)
				(anchor circle)
			)
			(primitives
				(gr_poly
					(pts
						(arc
							(start 0.1524 0.127)
							(mid 0.137521 0.162921)
							(end 0.1016 0.1778)
						)
						(arc
							(start -0.1016 0.1778)
							(mid -0.137521 0.162921)
							(end -0.1524 0.127)
						)
						(arc
							(start -0.1524 -0.127)
							(mid -0.137521 -0.162921)
							(end -0.1016 -0.1778)
						)
						(arc
							(start 0.1016 -0.1778)
							(mid 0.137521 -0.162921)
							(end 0.1524 -0.127)
						)
					)
					(width 0)
					(fill yes)
				)
			)
		)
	)
	(footprint ""
		(layer "B.Cu")
		(at 107.315 -44.2214 180)
		(property "Reference" "C74"
			(at 0 0 0)
			(layer "B.SilkS")
			(hide yes)
			(effects
				(font
					(size 1.27 1.27)
				)
				(justify mirror)
			)
		)
		(property "Value" "SCD01U16V1KX-GP"
			(at 2.8321 -1.7399 180)
			(unlocked yes)
			(layer "B.Fab")
			(hide yes)
			(effects
				(font
					(size 1.016 1.016)
					(thickness 0.1524)
				)
				(justify mirror)
			)
		)
		(property "Device Type" "C0201H13"
			(at 2.8321 -3.2639 180)
			(unlocked yes)
			(layer "B.Fab")
			(hide yes)
			(effects
				(font
					(size 1.016 1.016)
					(thickness 0.1524)
				)
				(justify mirror)
			)
		)
		(duplicate_pad_numbers_are_jumpers no)
		(fp_rect
			(start 0.2794 0.6477)
			(end -0.2794 -0.6477)
			(stroke
				(width 0)
				(type default)
			)
			(fill no)
			(layer "B.CrtYd")
		)
		(fp_rect
			(start 0.2794 0.6477)
			(end -0.2794 -0.6477)
			(stroke
				(width 0)
				(type default)
			)
			(fill no)
			(layer "B.Fab")
		)
		(pad "1" smd custom
			(at 0 -0.2794)
			(size 0.0762 0.0762)
			(layers "B.Cu" "B.Mask" "B.Paste")
			(net "PHY_DPB_TO_SCC_23_DN")
			(options
				(clearance outline)
				(anchor circle)
			)
			(primitives
				(gr_poly
					(pts
						(arc
							(start 0.1524 0.127)
							(mid 0.137521 0.162921)
							(end 0.1016 0.1778)
						)
						(arc
							(start -0.1016 0.1778)
							(mid -0.137521 0.162921)
							(end -0.1524 0.127)
						)
						(arc
							(start -0.1524 -0.127)
							(mid -0.137521 -0.162921)
							(end -0.1016 -0.1778)
						)
						(arc
							(start 0.1016 -0.1778)
							(mid 0.137521 -0.162921)
							(end 0.1524 -0.127)
						)
					)
					(width 0)
					(fill yes)
				)
			)
		)
		(pad "2" smd custom
			(at 0 0.2794)
			(size 0.0762 0.0762)
			(layers "B.Cu" "B.Mask" "B.Paste")
			(net "PHY_DPB_TO_SCC_C_23_DN")
			(options
				(clearance outline)
				(anchor circle)
			)
			(primitives
				(gr_poly
					(pts
						(arc
							(start 0.1524 0.127)
							(mid 0.137521 0.162921)
							(end 0.1016 0.1778)
						)
						(arc
							(start -0.1016 0.1778)
							(mid -0.137521 0.162921)
							(end -0.1524 0.127)
						)
						(arc
							(start -0.1524 -0.127)
							(mid -0.137521 -0.162921)
							(end -0.1016 -0.1778)
						)
						(arc
							(start 0.1016 -0.1778)
							(mid 0.137521 -0.162921)
							(end 0.1524 -0.127)
						)
					)
					(width 0)
					(fill yes)
				)
			)
		)
	)
	(footprint ""
		(layer "B.Cu")
		(at 107.88523 -58.6867 -90)
		(property "Reference" "C294"
			(at 0 0 90)
			(layer "B.SilkS")
			(hide yes)
			(effects
				(font
					(size 1.27 1.27)
				)
				(justify mirror)
			)
		)
		(property "Value" "SC1U6D3V1MX-GP"
			(at -1.9177 2.0193 270)
			(unlocked yes)
			(layer "B.Fab")
			(hide yes)
			(effects
				(font
					(size 1.016 1.016)
					(thickness 0.1524)
				)
				(justify mirror)
			)
		)
		(property "Device Type" "C0201H14"
			(at -1.9177 0.4953 270)
			(unlocked yes)
			(layer "B.Fab")
			(hide yes)
			(effects
				(font
					(size 1.016 1.016)
					(thickness 0.1524)
				)
				(justify mirror)
			)
		)
		(duplicate_pad_numbers_are_jumpers no)
		(fp_rect
			(start 0.1524 0.3048)
			(end -0.1524 -0.3048)
			(stroke
				(width 0)
				(type default)
			)
			(fill no)
			(layer "B.CrtYd")
		)
		(fp_poly
			(pts
				(xy 0.2794 0.6477) (xy 0.2794 -0.6477) (xy -0.2794 -0.6477) (xy -0.2794 -0.1905) (xy -0.1524 -0.1905)
				(xy -0.1524 -0.3048) (xy 0.1524 -0.3048) (xy 0.1524 0.3048) (xy -0.1524 0.3048) (xy -0.1524 -0.1778)
				(xy -0.2794 -0.1778) (xy -0.2794 0.6477)
			)
			(stroke
				(width 0)
				(type default)
			)
			(fill no)
			(layer "B.CrtYd")
		)
		(fp_rect
			(start 0.2794 0.6477)
			(end -0.2794 -0.6477)
			(stroke
				(width 0)
				(type default)
			)
			(fill no)
			(layer "B.Fab")
		)
		(pad "1" smd custom
			(at 0 -0.2794 90)
			(size 0.0762 0.0762)
			(layers "B.Cu" "B.Mask" "B.Paste")
			(net "GB_VDDA")
			(options
				(clearance outline)
				(anchor circle)
			)
			(primitives
				(gr_poly
					(pts
						(arc
							(start 0.1524 0.127)
							(mid 0.137521 0.162921)
							(end 0.1016 0.1778)
						)
						(arc
							(start -0.1016 0.1778)
							(mid -0.137521 0.162921)
							(end -0.1524 0.127)
						)
						(arc
							(start -0.1524 -0.127)
							(mid -0.137521 -0.162921)
							(end -0.1016 -0.1778)
						)
						(arc
							(start 0.1016 -0.1778)
							(mid 0.137521 -0.162921)
							(end 0.1524 -0.127)
						)
					)
					(width 0)
					(fill yes)
				)
			)
		)
		(pad "2" smd custom
			(at 0 0.2794 90)
			(size 0.0762 0.0762)
			(layers "B.Cu" "B.Mask" "B.Paste")
			(net "GND")
			(options
				(clearance outline)
				(anchor circle)
			)
			(primitives
				(gr_poly
					(pts
						(arc
							(start 0.1524 0.127)
							(mid 0.137521 0.162921)
							(end 0.1016 0.1778)
						)
						(arc
							(start -0.1016 0.1778)
							(mid -0.137521 0.162921)
							(end -0.1524 0.127)
						)
						(arc
							(start -0.1524 -0.127)
							(mid -0.137521 -0.162921)
							(end -0.1016 -0.1778)
						)
						(arc
							(start 0.1016 -0.1778)
							(mid 0.137521 -0.162921)
							(end 0.1524 -0.127)
						)
					)
					(width 0)
					(fill yes)
				)
			)
		)
	)
	(footprint ""
		(layer "B.Cu")
		(at 183.668416 -85.988652 90)
		(property "Reference" "C660"
			(at 0 0 90)
			(layer "B.SilkS")
			(hide yes)
			(effects
				(font
					(size 1.27 1.27)
				)
				(justify mirror)
			)
		)
		(property "Value" "SCD1U50V3KX-GP"
			(at 0 -2.8194 90)
			(unlocked yes)
			(layer "B.Fab")
			(hide yes)
			(effects
				(font
					(size 1.016 1.016)
					(thickness 0.1524)
				)
				(justify mirror)
			)
		)
		(property "Device Type" "C603H36"
			(at 0 -4.3434 90)
			(unlocked yes)
			(layer "B.Fab")
			(hide yes)
			(effects
				(font
					(size 1.016 1.016)
					(thickness 0.1524)
				)
				(justify mirror)
			)
		)
		(duplicate_pad_numbers_are_jumpers no)
		(fp_line
			(start -0.508 0)
			(end 0.508 0)
			(stroke
				(width 0.2032)
				(type default)
			)
			(layer "B.SilkS")
		)
		(fp_rect
			(start 0.5842 1.3335)
			(end -0.5842 -1.3335)
			(stroke
				(width 0)
				(type default)
			)
			(fill no)
			(layer "B.CrtYd")
		)
		(fp_rect
			(start 0.5842 1.3335)
			(end -0.5842 -1.3335)
			(stroke
				(width 0)
				(type default)
			)
			(fill no)
			(layer "B.Fab")
		)
		(pad "1" smd custom
			(at 0 -0.762 270)
			(size 0.2159 0.2159)
			(layers "B.Cu" "B.Mask" "B.Paste")
			(net "P0V975")
			(options
				(clearance outline)
				(anchor circle)
			)
			(primitives
				(gr_poly
					(pts
						(arc
							(start -0.3302 0.4318)
							(mid -0.402042 0.402042)
							(end -0.4318 0.3302)
						)
						(arc
							(start -0.4318 -0.3302)
							(mid -0.402042 -0.402042)
							(end -0.3302 -0.4318)
						)
						(arc
							(start 0.3302 -0.4318)
							(mid 0.402042 -0.402042)
							(end 0.4318 -0.3302)
						)
						(arc
							(start 0.4318 0.3302)
							(mid 0.402042 0.402042)
							(end 0.3302 0.4318)
						)
					)
					(width 0)
					(fill yes)
				)
			)
		)
		(pad "2" smd custom
			(at 0 0.762 270)
			(size 0.2159 0.2159)
			(layers "B.Cu" "B.Mask" "B.Paste")
			(net "GND")
			(options
				(clearance outline)
				(anchor circle)
			)
			(primitives
				(gr_poly
					(pts
						(arc
							(start -0.3302 0.4318)
							(mid -0.402042 0.402042)
							(end -0.4318 0.3302)
						)
						(arc
							(start -0.4318 -0.3302)
							(mid -0.402042 -0.402042)
							(end -0.3302 -0.4318)
						)
						(arc
							(start 0.3302 -0.4318)
							(mid 0.402042 -0.402042)
							(end 0.4318 -0.3302)
						)
						(arc
							(start 0.4318 0.3302)
							(mid 0.402042 0.402042)
							(end 0.3302 0.4318)
						)
					)
					(width 0)
					(fill yes)
				)
			)
		)
	)
	(footprint ""
		(layer "B.Cu")
		(at 121.2596 -57.4802)
		(property "Reference" "C259"
			(at 0 0 0)
			(layer "B.SilkS")
			(hide yes)
			(effects
				(font
					(size 1.27 1.27)
				)
				(justify mirror)
			)
		)
		(property "Value" "SCD1U6D3V1KX-GP"
			(at 2.8321 -1.7399 0)
			(unlocked yes)
			(layer "B.Fab")
			(hide yes)
			(effects
				(font
					(size 1.016 1.016)
					(thickness 0.1524)
				)
				(justify mirror)
			)
		)
		(property "Device Type" "C0201H13"
			(at 2.8321 -3.2639 0)
			(unlocked yes)
			(layer "B.Fab")
			(hide yes)
			(effects
				(font
					(size 1.016 1.016)
					(thickness 0.1524)
				)
				(justify mirror)
			)
		)
		(duplicate_pad_numbers_are_jumpers no)
		(fp_rect
			(start 0.2794 0.6477)
			(end -0.2794 -0.6477)
			(stroke
				(width 0)
				(type default)
			)
			(fill no)
			(layer "B.CrtYd")
		)
		(fp_rect
			(start 0.2794 0.6477)
			(end -0.2794 -0.6477)
			(stroke
				(width 0)
				(type default)
			)
			(fill no)
			(layer "B.Fab")
		)
		(pad "1" smd custom
			(at 0 -0.2794 180)
			(size 0.0762 0.0762)
			(layers "B.Cu" "B.Mask" "B.Paste")
			(net "GB_VDDA")
			(options
				(clearance outline)
				(anchor circle)
			)
			(primitives
				(gr_poly
					(pts
						(arc
							(start 0.1524 0.127)
							(mid 0.137521 0.162921)
							(end 0.1016 0.1778)
						)
						(arc
							(start -0.1016 0.1778)
							(mid -0.137521 0.162921)
							(end -0.1524 0.127)
						)
						(arc
							(start -0.1524 -0.127)
							(mid -0.137521 -0.162921)
							(end -0.1016 -0.1778)
						)
						(arc
							(start 0.1016 -0.1778)
							(mid 0.137521 -0.162921)
							(end 0.1524 -0.127)
						)
					)
					(width 0)
					(fill yes)
				)
			)
		)
		(pad "2" smd custom
			(at 0 0.2794 180)
			(size 0.0762 0.0762)
			(layers "B.Cu" "B.Mask" "B.Paste")
			(net "GND")
			(options
				(clearance outline)
				(anchor circle)
			)
			(primitives
				(gr_poly
					(pts
						(arc
							(start 0.1524 0.127)
							(mid 0.137521 0.162921)
							(end 0.1016 0.1778)
						)
						(arc
							(start -0.1016 0.1778)
							(mid -0.137521 0.162921)
							(end -0.1524 0.127)
						)
						(arc
							(start -0.1524 -0.127)
							(mid -0.137521 -0.162921)
							(end -0.1016 -0.1778)
						)
						(arc
							(start 0.1016 -0.1778)
							(mid 0.137521 -0.162921)
							(end 0.1524 -0.127)
						)
					)
					(width 0)
					(fill yes)
				)
			)
		)
	)
	(footprint ""
		(layer "B.Cu")
		(at 182.753 -26.1366 90)
		(property "Reference" "TP66"
			(at 0 0 90)
			(layer "B.SilkS")
			(hide yes)
			(effects
				(font
					(size 1.27 1.27)
				)
				(justify mirror)
			)
		)
		(property "Value" "TPAD28-2-GP"
			(at 0.0127 -1.6637 90)
			(unlocked yes)
			(layer "B.Fab")
			(hide yes)
			(effects
				(font
					(size 1.016 1.016)
					(thickness 0.1524)
				)
				(justify mirror)
			)
		)
		(property "Device Type" "TPAD28"
			(at 0.0127 -3.1877 90)
			(unlocked yes)
			(layer "B.Fab")
			(hide yes)
			(effects
				(font
					(size 1.016 1.016)
					(thickness 0.1524)
				)
				(justify mirror)
			)
		)
		(duplicate_pad_numbers_are_jumpers no)
		(fp_poly
			(pts
				(arc
					(start 0 0.3556)
					(mid 0 -0.3556)
					(end 0 0.3556)
				)
			)
			(stroke
				(width 0)
				(type default)
			)
			(fill no)
			(layer "B.CrtYd")
		)
		(fp_poly
			(pts
				(arc
					(start 0 0.6096)
					(mid 0 -0.6096)
					(end 0 0.6096)
				)
			)
			(stroke
				(width 0)
				(type default)
			)
			(fill no)
			(layer "B.Fab")
		)
		(pad "1" smd circle
			(at 0 0 270)
			(size 0.7112 0.7112)
			(layers "B.Cu" "B.Mask" "B.Paste")
			(net "IOC_GPIO_13")
		)
	)
)
